FILE_TYPE = MULTI_PHYS_TABLE;

PART 'MOSFET_NCH_GDS_ESD_PROTECTED'

{========================================================================================}
:VALUE         | PART_TYPE | MATERIAL | PART_NUMBER    = STANDARD    | LIFECYCLE     | PART_NUMBER   | JEDEC_TYPE                  | DESCRIPTION                                | MANUFTR | MANUF_PN      | RD_CMPLS_LVL | CMPLS_LVL | CLASS | DIP_SMD | FP_ECN | FROM_PJ        | DATA                         | EE_CHECK_LIST | STATUS | PSL | PREFERENCE | CREATOR | CREATEDAY  ;
{========================================================================================}
 'BSS138'      | 'SMLF'    | 'IC'     | 'BAM01380009'(!) = ''          | ''            | 'BAM01380009' |'SOT23_GDSXC'| 'TRANS MOSFET BSS138(50V,300MA,0.35W)'     | 'PJT'   | 'BSS138'      | 'EP(V1)'     | 'EP(V1)'  | 'IC'  | ''      | ''     | 'T2R-YAO-HSUN' | 'PJT_BSS138_rev0.pdf'        | ''            | ''     | ''  | ''         | ''      | '20140122'
 'BSS138'      | 'SMLF'    | 'EMPTY'  | 'BAM01380009'(!) = ''          | ''            | 'BAM01380009' |'SOT23_GDSXC'| 'TRANS MOSFET BSS138(50V,300MA,0.35W)'     | 'PJT'   | 'BSS138'      | 'EP(V1)'     | 'EP(V1)'  | 'IC'  | ''      | ''     | 'T2R-YAO-HSUN' | 'PJT_BSS138_rev0.pdf'        | ''            | ''     | ''  | ''         | ''      | '20140122'
 '2N7002K'     | 'SMLF'    | 'IC'     | 'BAM70020002'(!) = ''          | ''            | 'BAM70020002' |'SOT23_GDSXC'| 'TR MOSFET 2N7002K(60V,300MA,0.35W)SOT-23' | 'PJT'   | '2N7002K'     | 'EP(V1)'     | 'EP(V1)'  | 'IC'  | ''      | ''     | 'S1F-TONY'     | 'PJT_2N7002K.pdf'            | ''            | ''     | ''  | ''         | ''      | '20140122'
 '2N7002K'     | 'SMLF'    | 'EMPTY'  | 'BAM70020002'(!) = ''          | ''            | 'BAM70020002' |'SOT23_GDSXC'| 'TR MOSFET 2N7002K(60V,300MA,0.35W)SOT-23' | 'PJT'   | '2N7002K'     | 'EP(V1)'     | 'EP(V1)'  | 'IC'  | ''      | ''     | 'S1F-TONY'     | 'PJT_2N7002K.pdf'            | ''            | ''     | ''  | ''         | ''      | '20140122'
 '2N7002KW'    | 'SMLF'    | 'IC'     | 'BAM70020041'(!) = ''          | ''            | 'BAM70020041' |'SOT323XB'| 'TRANMOS 2N7002KW SOT323(60V, 115MA,0.2W)' | 'PJT'   | '2N7002KW'    | 'EP(V1)'     | 'EP(V1)'  | 'IC'  | ''      | ''     | 'MF1-EDDIE'    | 'PJT_2N7002KW.pdf'           | ''            | ''     | ''  | ''         | ''      | '20140122'
 '2N7002KW'    | 'SMLF'    | 'EMPTY'  | 'BAM70020041'(!) = ''          | ''            | 'BAM70020041' |'SOT323XB'| 'TRANMOS 2N7002KW SOT323(60V, 115MA,0.2W)' | 'PJT'   | '2N7002KW'    | 'EP(V1)'     | 'EP(V1)'  | 'IC'  | ''      | ''     | 'MF1-EDDIE'    | 'PJT_2N7002KW.pdf'           | ''            | ''     | ''  | ''         | ''      | '20140122'
 'BSS138BK'    | 'SMLF'    | 'IC'     | 'BAM01380018'(!) = ''          | ''            | 'BAM01380018' |'SOT23_GDSXE'| 'TRANS MOSFET BSS138BK(60V,0.35W)SOT23'    | 'NXP'   | 'BSS138BK'    | 'EP(V1)'     | 'EP(V1)'  | 'IC'  | ''      | ''     | 'UH3M-KEVIN'   | 'NXP_BSS138BK.pdf'           | ''            | ''     | ''  | ''         | ''      | '20150814'
 'BSS138BK'    | 'SMLF'    | 'EMPTY'  | 'BAM01380018'(!) = ''          | ''            | 'BAM01380018' |'SOT23_GDSXE'| 'TRANS MOSFET BSS138BK(60V,0.35W)SOT23'    | 'NXP'   | 'BSS138BK'    | 'EP(V1)'     | 'EP(V1)'  | 'IC'  | ''      | ''     | 'UH3M-KEVIN'   | 'NXP_BSS138BK.pdf'           | ''            | ''     | ''  | ''         | ''      | '20150814'
 'AO3416'      | 'SMLF'    | 'IC'     | 'BAM34160007'(!) = ''          | ''            | 'BAM34160007' |'SOT23_GDSXA'| 'TRANS MOSFET AO3416(20V,6.5A,1.4W)SOT23'  | 'AOS'   | 'AO3416'      | 'EP(V1)'     | 'EP(V1)'  | 'IC'  | ''      | ''     | 'MF1-TONY'     | 'AOS_AO3416.pdf'             | ''            | ''     | ''  | ''         | ''      | '20160223'
 'AO3416'      | 'SMLF'    | 'EMPTY'  | 'BAM34160007'(!) = ''          | ''            | 'BAM34160007' |'SOT23_GDSXA'| 'TRANS MOSFET AO3416(20V,6.5A,1.4W)SOT23'  | 'AOS'   | 'AO3416'      | 'EP(V1)'     | 'EP(V1)'  | 'IC'  | ''      | ''     | 'MF1-TONY'     | 'AOS_AO3416.pdf'             | ''            | ''     | ''  | ''         | ''      | '20160223'
 'DMG6968UQ-7' | 'SMLF'    | 'IC'     | 'BAM69680001'(!) = ''          | ''            | 'BAM69680001' |'SOT23_GDSXC'| 'TRANS MOS DMG6968UQ-7(20V,6.5A,1.3W)AEC'  | 'DDS'   | 'DMG6968UQ-7' | 'EP(V1)'     | ''        | 'IC'  | ''      | ''     | 'T2HV-RONNY'   | 'DDS_DMG6968UQ-7_REV6-2.pdf' | ''            | ''     | ''  | ''         | ''      | '20160317'
 'DMG6968UQ-7' | 'SMLF'    | 'EMPTY'  | 'BAM69680001'(!) = ''          | ''            | 'BAM69680001' |'SOT23_GDSXC'| 'TRANS MOS DMG6968UQ-7(20V,6.5A,1.3W)AEC'  | 'DDS'   | 'DMG6968UQ-7' | 'EP(V1)'     | ''        | 'IC'  | ''      | ''     | 'T2HV-RONNY'   | 'DDS_DMG6968UQ-7_REV6-2.pdf' | ''            | ''     | ''  | ''         | ''      | '20160317'
 'DMN61D9UW-7' | 'SMLF'    | 'IC'     | 'BAM61D90001'(!) = 'Potential' | 'End of Life' | 'BAM61D90001' |'SOT323_GDS_2-15X1-3XA_EOL'| 'TRANS MOS DMN61D9UW-7(60V,0.34A,0.32W)'   | 'DDS'   | 'DMN61D9UW-7' | 'EP(V1)'     | ''        | 'IC'  | ''      | ''     | 'T2MK-FRANK'   | 'DDS_DMN61D9UW-7.pdf'        | ''            | ''     | ''  | ''         | ''      | '20171213'
 'DMN61D9UW-7' | 'SMLF'    | 'EMPTY'  | 'BAM61D90001'(!) = 'Potential' | 'End of Life' | 'BAM61D90001' |'SOT323_GDS_2-15X1-3XA_EOL'| 'TRANS MOS DMN61D9UW-7(60V,0.34A,0.32W)'   | 'DDS'   | 'DMN61D9UW-7' | 'EP(V1)'     | ''        | 'IC'  | ''      | ''     | 'T2MK-FRANK'   | 'DDS_DMN61D9UW-7.pdf'        | ''            | ''     | ''  | ''         | ''      | '20171213'
 'DMN53D0L-7'  | 'SMLF'    | 'IC'     | 'BAM53D00000'(!) = ''          | ''            | 'BAM53D00000' |'SOT23_GDSXC'| 'TRANS MOSFET DMN53D0L-7(50V,0.5A,0.5W)'   | 'DDS'   | 'DMN53D0L-7'  | 'EP(V1)'     | 'EP(V1)'  | 'IC'  | ''      | ''     | 'JBP-JACK'     | 'DDS_DMN53D0L-7.pdf'         | ''            | ''     | ''  | ''         | ''      | '20190104'
 'DMN53D0L-7'  | 'SMLF'    | 'EMPTY'  | 'BAM53D00000'(!) = ''          | ''            | 'BAM53D00000' |'SOT23_GDSXC'| 'TRANS MOSFET DMN53D0L-7(50V,0.5A,0.5W)'   | 'DDS'   | 'DMN53D0L-7'  | 'EP(V1)'     | 'EP(V1)'  | 'IC'  | ''      | ''     | 'JBP-JACK'     | 'DDS_DMN53D0L-7.pdf'         | ''            | ''     | ''  | ''         | ''      | '20190104'
 '2N7002KTB'   | 'SMLF'    | 'IC'     | 'BAN70020007'(!) = ''          | ''            | 'BAN70020007' |'SOT523_GDS_1-6X1-2'| 'TRANS MOS 2N7002KTB (60V,0.115A,0.2W)'    | 'PJT'   | '2N7002KTB'   | 'EP(V1)'     | 'EP(V1)'  | 'IC'  | ''      | ''     | 'S5Z-ERIC'     | 'PJT_2N7002KTB.pdf'          | ''            | ''     | ''  | ''         | ''      | '20200714'
 '2N7002KTB'   | 'SMLF'    | 'EMPTY'  | 'BAN70020007'(!) = ''          | ''            | 'BAN70020007' |'SOT523_GDS_1-6X1-2'| 'TRANS MOS 2N7002KTB (60V,0.115A,0.2W)'    | 'PJT'   | '2N7002KTB'   | 'EP(V1)'     | 'EP(V1)'  | 'IC'  | ''      | ''     | 'S5Z-ERIC'     | 'PJT_2N7002KTB.pdf'          | ''            | ''     | ''  | ''         | ''      | '20200714'
 'PJC138K'     | 'SMLF'    | 'IC'     | 'BAM138K0002'(!) = ''          | ''            | 'BAM138K0002' |'SOT323_GDS_2X1-25'| 'TRANS MOSFET PJC138K(50V,0.36A,0.236W)'   | 'PJT'   | 'PJC138K'     | 'EP(V1)'     | 'EP(V1)'  | 'IC'  | ''      | ''     | 'S9T-CHI-LIN'  | 'PJT_2N7002KTB.pdf'          | ''            | ''     | ''  | ''         | ''      | '20210331'
 'PJC138K'     | 'SMLF'    | 'EMPTY'  | 'BAM138K0002'(!) = ''          | ''            | 'BAM138K0002' |'SOT323_GDS_2X1-25'| 'TRANS MOSFET PJC138K(50V,0.36A,0.236W)'   | 'PJT'   | 'PJC138K'     | 'EP(V1)'     | 'EP(V1)'  | 'IC'  | ''      | ''     | 'S9T-CHI-LIN'  | 'PJT_2N7002KTB.pdf'          | ''            | ''     | ''  | ''         | ''      | '20210331'
 'DMN53D0U-7'  | 'SMLF'    | 'IC'     | 'BAM3D0U0000'(!) = ''               | ''               | 'BAM3D0U0000' |'SOT23_GDSXC'| 'TRANS MOS DMN53D0U-7(50V,0.3/0.2A,0.52W)' | 'DDS'   | 'DMN53D0U-7'  | 'EP(V1)'     | ''        | 'IC'  | ''      | ''     | 'S8G-MICHAEL'  | 'DDS_DMN53D0U-7.pdf'         | ''            | ''     | ''  | ''         | ''      | '20230321'
 'DMN53D0U-7'  | 'SMLF'    | 'EMPTY'  | 'BAM3D0U0000'(!) = ''               | ''               | 'BAM3D0U0000' |'SOT23_GDSXC'| 'TRANS MOS DMN53D0U-7(50V,0.3/0.2A,0.52W)' | 'DDS'   | 'DMN53D0U-7'  | 'EP(V1)'     | ''        | 'IC'  | ''      | ''     | 'S8G-MICHAEL'  | 'DDS_DMN53D0U-7.pdf'         | ''            | ''     | ''  | ''         | ''      | '20230321'

END_PART

END.

